# T6G (Grand Teton) — schematic netlist excerpt (pin names and nets, part order shuffled) for the footprints in the layout excerpt that follows; sources: Cadence DE-HDL packaged netlist, KiCad conversion of 04192023_DAF0TMB3IC0_F0TG_MB_C_brd_V02_OCP.brd

X9009  TP_TDR_4P_FTS  TP_TDR_4P_DIP EMPTY  pkg TH  page 261
  S1  = TDR_DIFF_85_NECK_IN2_DN
  P1  = T1_GND
  P2  = T1_GND
  S2  = TDR_DIFF_85_NECK_IN2_DP

R4015  Q_RES  100K 1% CHIP  pkg 0402LF  page 152 : A = P3V3_AUX ; B = HP_LVC3_SCM_HSC_PWRGD

(kicad_pcb
	(version 20260206)
	(generator "pcbnew")
	(generator_version "10.0")
	(general
		(thickness 1.6)
		(legacy_teardrops no)
	)
	(paper "A4")
	(title_block
		(title "04192023_DAF0TMB3IC0_F0TG_MB_C_brd_V02_OCP.brd")
		(comment 1 "Grand Teton / footprints 181-182 of 8354")
	)
	(layers
		(0 "F.Cu" signal "TOP")
		(4 "In1.Cu" signal "GND")
		(6 "In2.Cu" signal "IN1")
		(8 "In3.Cu" signal "GND1")
		(10 "In4.Cu" signal "IN2")
		(12 "In5.Cu" signal "GND2")
		(14 "In6.Cu" signal "IN3")
		(16 "In7.Cu" signal "GND3")
		(18 "In8.Cu" signal "VCC")
		(20 "In9.Cu" signal "VCC1")
		(22 "In10.Cu" signal "GND4")
		(24 "In11.Cu" signal "IN4")
		(26 "In12.Cu" signal "GND5")
		(28 "In13.Cu" signal "IN5")
		(30 "In14.Cu" signal "GND6")
		(32 "In15.Cu" signal "IN6")
		(34 "In16.Cu" signal "GND7")
		(2 "B.Cu" signal "BOTTOM")
		(9 "F.Adhes" user "F.Adhesive")
		(11 "B.Adhes" user "B.Adhesive")
		(13 "F.Paste" user "Package Geometry/Pastemask Top")
		(15 "B.Paste" user "Package Geometry/Pastemask Bottom")
		(5 "F.SilkS" user "Ref Des/Silkscreen Top")
		(7 "B.SilkS" user "Ref Des/Silkscreen Bottom")
		(1 "F.Mask" user "Board Geometry/Soldermask Top")
		(3 "B.Mask" user "Board Geometry/Soldermask Bottom")
		(17 "Dwgs.User" user "User.Drawings")
		(19 "Cmts.User" user "User.Comments")
		(21 "Eco1.User" user "User.Eco1")
		(23 "Eco2.User" user "User.Eco2")
		(25 "Edge.Cuts" user "Board Geometry/Outline")
		(27 "Margin" user)
		(31 "F.CrtYd" user "Package Geometry/Place Bound Top")
		(29 "B.CrtYd" user "Package Geometry/Place Bound Bottom")
		(35 "F.Fab" user "Ref Des/Assembly Top")
		(33 "B.Fab" user "Ref Des/Assembly Bottom")
	)
	(footprint ""
		(layer "F.Cu")
		(at 193.089022 -24.091392 -90)
		(property "Reference" "R4015"
			(at 0 0 270)
			(layer "F.SilkS")
			(hide yes)
			(effects
				(font
					(size 1.27 1.27)
				)
			)
		)
		(property "Value" ""
			(at 0 0 270)
			(layer "F.Fab")
			(effects
				(font
					(size 1.27 1.27)
				)
			)
		)
		(duplicate_pad_numbers_are_jumpers no)
		(fp_line
			(start -0.7874 0.4064)
			(end -0.7874 -0.4064)
			(stroke
				(width 0.1524)
				(type default)
			)
			(layer "F.SilkS")
		)
		(fp_line
			(start 0.7874 0.4064)
			(end -0.7874 0.4064)
			(stroke
				(width 0.1524)
				(type default)
			)
			(layer "F.SilkS")
		)
		(fp_line
			(start -0.7874 -0.4064)
			(end 0.7874 -0.4064)
			(stroke
				(width 0.1524)
				(type default)
			)
			(layer "F.SilkS")
		)
		(fp_line
			(start 0.7874 -0.4064)
			(end 0.7874 0.4064)
			(stroke
				(width 0.1524)
				(type default)
			)
			(layer "F.SilkS")
		)
		(fp_line
			(start -0.67945 0.3048)
			(end -0.67945 -0.305054)
			(stroke
				(width 0.1)
				(type default)
			)
			(layer "F.Fab")
		)
		(fp_line
			(start -0.12065 0.3048)
			(end -0.67945 0.3048)
			(stroke
				(width 0.1)
				(type default)
			)
			(layer "F.Fab")
		)
		(fp_line
			(start 0.120396 0.3048)
			(end 0.120396 0.2794)
			(stroke
				(width 0.1)
				(type default)
			)
			(layer "F.Fab")
		)
		(fp_line
			(start 0.67945 0.3048)
			(end 0.120396 0.3048)
			(stroke
				(width 0.1)
				(type default)
			)
			(layer "F.Fab")
		)
		(fp_line
			(start -0.12065 0.2794)
			(end -0.12065 0.3048)
			(stroke
				(width 0.1)
				(type default)
			)
			(layer "F.Fab")
		)
		(fp_line
			(start 0.120396 0.2794)
			(end -0.12065 0.2794)
			(stroke
				(width 0.1)
				(type default)
			)
			(layer "F.Fab")
		)
		(fp_line
			(start -0.12065 -0.2794)
			(end 0.12065 -0.2794)
			(stroke
				(width 0.1)
				(type default)
			)
			(layer "F.Fab")
		)
		(fp_line
			(start 0.12065 -0.2794)
			(end 0.12065 -0.3048)
			(stroke
				(width 0.1)
				(type default)
			)
			(layer "F.Fab")
		)
		(fp_line
			(start 0.12065 -0.3048)
			(end 0.67945 -0.3048)
			(stroke
				(width 0.1)
				(type default)
			)
			(layer "F.Fab")
		)
		(fp_line
			(start 0.67945 -0.3048)
			(end 0.67945 0.3048)
			(stroke
				(width 0.1)
				(type default)
			)
			(layer "F.Fab")
		)
		(fp_line
			(start -0.67945 -0.305054)
			(end -0.12065 -0.305054)
			(stroke
				(width 0.1)
				(type default)
			)
			(layer "F.Fab")
		)
		(fp_line
			(start -0.12065 -0.305054)
			(end -0.12065 -0.2794)
			(stroke
				(width 0.1)
				(type default)
			)
			(layer "F.Fab")
		)
		(pad "1" smd circle
			(at -0.40005 0 270)
			(size 0 0)
			(layers "F.Cu" "F.Mask" "F.Paste")
			(net "P3V3_AUX")
		)
		(pad "2" smd circle
			(at 0.40005 0 270)
			(size 0 0)
			(layers "F.Cu" "F.Mask" "F.Paste")
			(net "HP_LVC3_SCM_HSC_PWRGD")
		)
	)
	(footprint ""
		(layer "F.Cu")
		(at 492.985044 -457.29398 90)
		(property "Reference" "X9009"
			(at -1.979168 1.12141 0)
			(unlocked yes)
			(layer "F.SilkS")
			(effects
				(font
					(size 0.7874 0.5842)
					(thickness 0.1524)
				)
				(justify left)
			)
		)
		(property "Value" ""
			(at 0 0 90)
			(layer "F.Fab")
			(effects
				(font
					(size 1.27 1.27)
				)
			)
		)
		(property "User Part Number" "N_A"
			(at 1.30175 1.27 180)
			(unlocked yes)
			(layer "Cmts.User")
			(hide yes)
			(effects
				(font
					(size 0.635 0.4064)
					(thickness 0.1524)
				)
			)
		)
		(property "Device Type" "TP_TDR_4P_FTS_TH-TP_TDR_4P_DIP,EMPTY,TP15"
			(at 1.30175 1.27 180)
			(unlocked yes)
			(layer "F.Fab")
			(hide yes)
			(effects
				(font
					(size 0.635 0.4064)
					(thickness 0.1524)
				)
			)
		)
		(duplicate_pad_numbers_are_jumpers no)
		(fp_line
			(start 2.54 -1.27)
			(end 0 -1.27)
			(stroke
				(width 0.1524)
				(type default)
			)
			(layer "F.SilkS")
		)
		(fp_line
			(start 0 -1.27)
			(end 0 -0.635)
			(stroke
				(width 0.1524)
				(type default)
			)
			(layer "F.SilkS")
		)
		(fp_line
			(start 2.54 -1.1303)
			(end 2.54 -1.27)
			(stroke
				(width 0.1524)
				(type default)
			)
			(layer "F.SilkS")
		)
		(fp_line
			(start 0 0.635)
			(end 0 1.905)
			(stroke
				(width 0.1524)
				(type default)
			)
			(layer "F.SilkS")
		)
		(fp_line
			(start 2.54 1.4097)
			(end 2.54 1.1303)
			(stroke
				(width 0.1524)
				(type default)
			)
			(layer "F.SilkS")
		)
		(fp_line
			(start 0 3.175)
			(end 0 3.81)
			(stroke
				(width 0.1524)
				(type default)
			)
			(layer "F.SilkS")
		)
		(fp_line
			(start 2.54 3.81)
			(end 2.54 3.6703)
			(stroke
				(width 0.1524)
				(type default)
			)
			(layer "F.SilkS")
		)
		(fp_line
			(start 0 3.81)
			(end 2.54 3.81)
			(stroke
				(width 0.1524)
				(type default)
			)
			(layer "F.SilkS")
		)
		(fp_poly
			(pts
				(xy -2.285746 -0.762) (xy -0.761746 0) (xy -2.285746 0.762)
			)
			(stroke
				(width 0)
				(type default)
			)
			(fill yes)
			(layer "F.SilkS")
		)
		(fp_line
			(start 2.54 -1.27)
			(end 0 -1.27)
			(stroke
				(width 0.1)
				(type default)
			)
			(layer "F.Fab")
		)
		(fp_line
			(start 0 -1.27)
			(end 0 3.81)
			(stroke
				(width 0.1)
				(type default)
			)
			(layer "F.Fab")
		)
		(fp_line
			(start 2.54 3.81)
			(end 2.54 -1.27)
			(stroke
				(width 0.1)
				(type default)
			)
			(layer "F.Fab")
		)
		(fp_line
			(start 0 3.81)
			(end 2.54 3.81)
			(stroke
				(width 0.1)
				(type default)
			)
			(layer "F.Fab")
		)
		(fp_poly
			(pts
				(xy -0.761746 0) (xy -2.285746 -0.762) (xy -2.285746 0.762)
			)
			(stroke
				(width 0)
				(type default)
			)
			(fill yes)
			(layer "F.Fab")
		)
		(pad "1" thru_hole circle
			(at 0 0 90)
			(size 1.0033 1.0033)
			(drill 0.249936)
			(layers "*.Cu" "*.Mask")
			(remove_unused_layers no)
			(net "TDR_DIFF_85_NECK_IN2_DN")
			(clearance 0.10795)
			(thermal_gap 0.10795)
			(padstack
				(mode front_inner_back)
				(layer "Inner"
					(shape circle)
					(size 0.8001 0.8001)
					(clearance 0.1524)
				)
				(layer "B.Cu"
					(shape circle)
					(size 1.0033 1.0033)
					(clearance 0.10795)
				)
			)
		)
		(pad "2" thru_hole circle
			(at 2.54 0 90)
			(size 1.9939 1.9939)
			(drill 0.249936)
			(layers "*.Cu" "*.Mask")
			(remove_unused_layers no)
			(net "T1_GND")
			(clearance 0.10795)
			(thermal_gap 0.10795)
			(padstack
				(mode front_inner_back)
				(layer "Inner"
					(shape circle)
					(size 0.8001 0.8001)
					(clearance 0.1524)
				)
				(layer "B.Cu"
					(shape circle)
					(size 1.9939 1.9939)
					(clearance 0.10795)
				)
			)
		)
		(pad "3" thru_hole circle
			(at 2.54 2.54 90)
			(size 1.9939 1.9939)
			(drill 0.249936)
			(layers "*.Cu" "*.Mask")
			(remove_unused_layers no)
			(net "T1_GND")
			(clearance 0.10795)
			(thermal_gap 0.10795)
			(padstack
				(mode front_inner_back)
				(layer "Inner"
					(shape circle)
					(size 0.8001 0.8001)
					(clearance 0.1524)
				)
				(layer "B.Cu"
					(shape circle)
					(size 1.9939 1.9939)
					(clearance 0.10795)
				)
			)
		)
		(pad "4" thru_hole circle
			(at 0 2.54 90)
			(size 1.0033 1.0033)
			(drill 0.249936)
			(layers "*.Cu" "*.Mask")
			(remove_unused_layers no)
			(net "TDR_DIFF_85_NECK_IN2_DP")
			(clearance 0.10795)
			(thermal_gap 0.10795)
			(padstack
				(mode front_inner_back)
				(layer "Inner"
					(shape circle)
					(size 0.8001 0.8001)
					(clearance 0.1524)
				)
				(layer "B.Cu"
					(shape circle)
					(size 1.0033 1.0033)
					(clearance 0.10795)
				)
			)
		)
	)
)
